FILE_TYPE = CONNECTIVITY;
{Allegro Design Entry HDL 16.6-p007 (v16-6-112F) 10/10/2012}
"PAGE_NUMBER" = 89;
0"NC";
1"GND\g";
2"PVPP_ABC\g";
3"P3V3_STBY\g";
4"P3V3_STBY\g";
5"GND\g";
6"GND\g";
7"FM_ADR_SMI_GPIO_N";
8"IRQ_DIMM_SAVE_LVT3_N";
9"IRQ_DIMM_SAVE_LVT3";
10"IRQ_DIMM_SAVE_R_N";
11"FM_ADR_COMPLETE_ABC_N";
12"FM_ADR_COMPLETE_DEF_N";
13"IRQ_DIMM_SAVE_N";
14"FM_ADR_COMPLETE_GHJ_N";
15"FM_ADR_COMPLETE_KLM_N";
16"FM_ADR_COMPLETE_R";
17"FM_ADR_COMPLETE_DLY";
18"FM_ADR_COMPLETE";
%"RES"
"1","(-1650,2400)","0","mstr_discrete","I1";
;
CDS_SEC"1"
BOM_COST"MEM_NV"
SEC_TYPE"0402"
ROOM"NV_DIMM"
SEC"1"
CDS_LIB"mstr_discrete"
CDS_LOCATION"R4T2"
PACK_TYPE"0402"
MATERIAL"EMPTY"
PART_NUMBER"G21497-005"
LOCATION"R4T2"
VALUE"0.0"
TOLERANCE"5%"
WATTAGE"1/16W";
"B"
$PN"2"16;
"A"
$PN"1"18;
%"GND"
"1","(-550,1900)","0","mstr_symbols","I16";
;
HDL_POWER"GND"
SIZE"1B"
CDS_LIB"mstr_symbols"
BODY_TYPE"PLUMBING"
VOLTAGE"0.0V";
"A\NAC"1;
%"PVPP_ABC"
"1","(-550,2950)","0","mstr_symbols","I17";
;
VOLTAGE"2.5V"
CDS_LIB"mstr_symbols"
BODY_TYPE"PLUMBING"
HDL_POWER"PVPP_ABC";
"G\NAC"2;
%"FET_N"
"8","(-550,2200)","0","mstr_discrete","I18";
;
CDS_SEC"1"
SEC_TYPE"SOT23"
BOM_COST"MEM_NV"
SEC"1"
ROOM"NVDIMM"
CDS_LOCATION"Q6F1"
PACK_TYPE"SOT23"
CDS_LIB"mstr_discrete"
LOCATION"Q6F1"
VALUE"2N7002"
MATERIAL"FET"
PART_NUMBER"C79254-001";
"GATE"
$PN"1"16;
"DRN"
$PN"3"13;
"SRC"
$PN"2"1;
%"RES"
"1","(-1650,2100)","0","mstr_discrete","I2";
;
CDS_SEC"1"
SEC_TYPE"0402"
BOM_COST"MEM_NV"
CDS_LIB"mstr_discrete"
SEC"1"
CDS_LOCATION"R4T1"
ROOM"NV_DIMM"
PART_NUMBER"G21497-005"
LOCATION"R4T1"
WATTAGE"1/16W"
MATERIAL"CHIP"
PACK_TYPE"0402"
TOLERANCE"5%"
VALUE"0.0";
"B"
$PN"2"16;
"A"
$PN"1"17;
%"RES"
"1","(3325,2900)","0","mstr_discrete","I23";
;
BOM_COST"MEM_NV"
CDS_SEC"1"
$SEC"1"
ROOM"NV_DIMM"
CDS_LOCATION"R2P12"
CDS_LIB"mstr_discrete"
PACK_TYPE"0402"
MATERIAL"EMPTY"
LOCATION"R2P12"
PART_NUMBER"G21497-005"
TOLERANCE"5%"
VALUE"0.0"
WATTAGE"1/16W";
"B"
$PN"2"7;
"A"
$PN"1"8;
%"RES"
"2","(1850,3875)","0","mstr_discrete","I26";
;
CDS_SEC"1"
$SEC"1"
ROOM"NVDIMM"
CDS_LOCATION"R8D29"
CDS_LIB"mstr_discrete"
PART_NUMBER"G21796-072"
LOCATION"R8D29"
VALUE"4.75K"
TOLERANCE"1%"
WATTAGE"1/16W"
PACK_TYPE"0402"
MATERIAL"CHIP";
"A"
$PN"1"3;
"B"
$PN"2"9;
%"RES"
"2","(2550,4100)","0","mstr_discrete","I27";
;
CDS_SEC"1"
$SEC"1"
CDS_LOCATION"R8D31"
ROOM"NVDIMM"
CDS_LIB"mstr_discrete"
LOCATION"R8D31"
VALUE"4.75K"
TOLERANCE"1%"
WATTAGE"1/16W"
PART_NUMBER"G21796-072"
PACK_TYPE"0402"
MATERIAL"CHIP";
"A"
$PN"1"4;
"B"
$PN"2"8;
%"P3V3_STBY"
"1","(1850,4100)","0","mstr_symbols","I28";
;
CDS_LIB"mstr_symbols"
SIZE"1B"
BODY_TYPE"PLUMBING"
VOLTAGE"3.3V"
HDL_POWER"P3V3_STBY";
"G\NAC"3;
%"P3V3_STBY"
"1","(2550,4325)","0","mstr_symbols","I29";
;
SIZE"1B"
HDL_POWER"P3V3_STBY"
CDS_LIB"mstr_symbols"
VOLTAGE"3.3V"
BODY_TYPE"PLUMBING";
"G\NAC"4;
%"RES"
"1","(450,2500)","0","mstr_discrete","I3";
;
CDS_SEC"1"
BOM_COST"MEM_NV"
SEC_TYPE"0402"
SEC"1"
ROOM"NV_DIMM"
CDS_LOCATION"R6F4"
CDS_LIB"mstr_discrete"
PACK_TYPE"0402"
LOCATION"R6F4"
PART_NUMBER"G21796-047"
MATERIAL"CHIP"
TOLERANCE"1%"
WATTAGE"1/16W"
VALUE"49.9";
"B"
$PN"2"11;
"A"
$PN"1"13;
%"GND"
"1","(2550,3325)","0","mstr_symbols","I30";
;
SIZE"1B"
HDL_POWER"GND"
CDS_LIB"mstr_symbols"
VOLTAGE"0.0V"
BODY_TYPE"PLUMBING";
"A\NAC"5;
%"GND"
"1","(1850,2850)","0","mstr_symbols","I31";
;
HDL_POWER"GND"
CDS_LIB"mstr_symbols"
VOLTAGE"0.0V"
BODY_TYPE"PLUMBING"
SIZE"1B";
"A\NAC"6;
%"RES"
"1","(875,3075)","0","mstr_discrete","I34";
;
CDS_SEC"1"
ROOM"NV_DIMM"
CDS_LOCATION"R8D30"
SEC"1"
BOM_COST"MEM_NV"
CDS_LIB"mstr_discrete"
SEC_TYPE"0402"
PACK_TYPE"0402"
PART_NUMBER"G21796-016"
LOCATION"R8D30"
VALUE"10.0K"
TOLERANCE"1%"
MATERIAL"CHIP"
WATTAGE"1/16W";
"B"
$PN"2"10;
"A"
$PN"1"13;
%"NPN_DUAL"
"1","(1800,3075)","0","mstr_discrete","I35";
;
CDS_SEC"1"
PACK_TYPE"SSOPLF"
BOM_COST"MEM_NV"
SEC_TYPE"SSOPLF"
CDS_LIB"mstr_discrete"
SEC"1"
CDS_LOCATION"Q8D1"
ROOM"NV_DIMM"
PART_NUMBER"C52264-001"
VALUE"MBT3904"
LOCATION"Q8D1"
MATERIAL"XSTR";
"C <SIZE-1..0>"
$PN"3"9;
"B <SIZE-1..0>"
$PN"5"10;
"E <SIZE-1..0>"
$PN"4"6;
%"NPN_DUAL"
"1","(2500,3550)","0","mstr_discrete","I36";
;
CDS_SEC"2"
PACK_TYPE"SSOPLF"
BOM_COST"MEM_NV"
SEC_TYPE"SSOPLF"
SEC"2"
CDS_LOCATION"Q8D1"
ROOM"NV_DIMM"
CDS_LIB"mstr_discrete"
LOCATION"Q8D1"
VALUE"MBT3904"
MATERIAL"XSTR"
PART_NUMBER"C52264-001";
"C <SIZE-1..0>"
$PN"6"8;
"B <SIZE-1..0>"
$PN"2"9;
"E <SIZE-1..0>"
$PN"1"5;
%"RES"
"1","(450,2200)","0","mstr_discrete","I4";
;
CDS_SEC"1"
ROOM"NV_DIMM"
SEC"1"
SEC_TYPE"0402"
BOM_COST"MEM_NV"
CDS_LIB"mstr_discrete"
CDS_LOCATION"R6F1"
PACK_TYPE"0402"
LOCATION"R6F1"
PART_NUMBER"G21796-047"
MATERIAL"CHIP"
TOLERANCE"1%"
WATTAGE"1/16W"
VALUE"49.9";
"B"
$PN"2"12;
"A"
$PN"1"13;
%"RES"
"1","(450,1900)","0","mstr_discrete","I5";
;
CDS_SEC"1"
SEC_TYPE"0402"
BOM_COST"MEM_NV"
SEC"1"
ROOM"NV_DIMM"
CDS_LOCATION"R6F5"
CDS_LIB"mstr_discrete"
PACK_TYPE"0402"
LOCATION"R6F5"
PART_NUMBER"G21796-047"
MATERIAL"CHIP"
TOLERANCE"1%"
VALUE"49.9"
WATTAGE"1/16W";
"B"
$PN"2"14;
"A"
$PN"1"13;
%"RES"
"1","(450,1600)","0","mstr_discrete","I6";
;
CDS_SEC"1"
SEC_TYPE"0402"
BOM_COST"MEM_NV"
ROOM"NV_DIMM"
CDS_LOCATION"R6F2"
SEC"1"
CDS_LIB"mstr_discrete"
PACK_TYPE"0402"
LOCATION"R6F2"
PART_NUMBER"G21796-047"
MATERIAL"CHIP"
VALUE"49.9"
TOLERANCE"1%"
WATTAGE"1/16W";
"B"
$PN"2"15;
"A"
$PN"1"13;
%"RES"
"2","(-550,2700)","0","mstr_discrete","I7";
;
CDS_SEC"1"
SEC"1"
SEC_TYPE"0402"
BOM_COST"MEM_NV"
ROOM"NV_DIMM"
CDS_LOCATION"R6F3"
CDS_LIB"mstr_discrete"
MATERIAL"CHIP"
WATTAGE"1/16W"
PART_NUMBER"G21796-016"
LOCATION"R6F3"
TOLERANCE"1%"
VALUE"10.0K"
PACK_TYPE"0402";
"A"
$PN"1"2;
"B"
$PN"2"13;
END.
